# SCM (Grand Teton) — schematic netlist excerpt (pin names and nets, part order shuffled) for the footprints in the layout excerpt that follows; sources: Cadence DE-HDL packaged netlist, KiCad conversion of 12092022_DA0F0TMDCD0_F0T_Management_Board_D_brd_V3_OCP.brd

R650  Q_RES  33.2 1% EMPTY  pkg 0402LF  page 21 : A = BMC_EMMC_DT7 ; B = EMMC_DT7_R
PL33  Q_INDUCTOR  1UH IND  pkg SMLF  page 56 : \1\ = SW_P1V0_AUX_SW ; \2\ = P1V0_AUX
R107  Q_RES  316 1% CHIP  pkg 0402LF  page 50 : A = LED_D21_R3 ; B = LED_D21_R2

(kicad_pcb
	(version 20260206)
	(generator "pcbnew")
	(generator_version "10.0")
	(general
		(thickness 1.6)
		(legacy_teardrops no)
	)
	(paper "A4")
	(title_block
		(title "12092022_DA0F0TMDCD0_F0T_Management_Board_D_brd_V3_OCP.brd")
		(comment 1 "Grand Teton / footprints 696-698 of 1440")
	)
	(layers
		(0 "F.Cu" signal "TOP")
		(4 "In1.Cu" signal "GND")
		(6 "In2.Cu" signal "IN1")
		(8 "In3.Cu" signal "GND1")
		(10 "In4.Cu" signal "IN2")
		(12 "In5.Cu" signal "VCC")
		(14 "In6.Cu" signal "VCC1")
		(16 "In7.Cu" signal "IN3")
		(18 "In8.Cu" signal "GND2")
		(20 "In9.Cu" signal "IN4")
		(22 "In10.Cu" signal "GND3")
		(2 "B.Cu" signal "BOTTOM")
		(9 "F.Adhes" user "F.Adhesive")
		(11 "B.Adhes" user "B.Adhesive")
		(13 "F.Paste" user "Package Geometry/Pastemask Top")
		(15 "B.Paste" user "Package Geometry/Pastemask Bottom")
		(5 "F.SilkS" user "Ref Des/Silkscreen Top")
		(7 "B.SilkS" user "Ref Des/Silkscreen Bottom")
		(1 "F.Mask" user "Board Geometry/Soldermask Top")
		(3 "B.Mask" user "Board Geometry/Soldermask Bottom")
		(17 "Dwgs.User" user "User.Drawings")
		(19 "Cmts.User" user "User.Comments")
		(21 "Eco1.User" user "User.Eco1")
		(23 "Eco2.User" user "User.Eco2")
		(25 "Edge.Cuts" user "Board Geometry/Outline")
		(27 "Margin" user)
		(31 "F.CrtYd" user "Package Geometry/Place Bound Top")
		(29 "B.CrtYd" user "Package Geometry/Place Bound Bottom")
		(35 "F.Fab" user "Ref Des/Assembly Top")
		(33 "B.Fab" user "Ref Des/Assembly Bottom")
	)
	(footprint ""
		(layer "F.Cu")
		(at 21.168614 -25.111202 -90)
		(property "Reference" "PL33"
			(at 0 0 270)
			(layer "F.SilkS")
			(hide yes)
			(effects
				(font
					(size 1.27 1.27)
				)
			)
		)
		(property "Value" ""
			(at 0 0 270)
			(layer "F.Fab")
			(effects
				(font
					(size 1.27 1.27)
				)
			)
		)
		(duplicate_pad_numbers_are_jumpers no)
		(fp_line
			(start -3.64998 3.350006)
			(end -3.64998 1.8288)
			(stroke
				(width 0.1524)
				(type default)
			)
			(layer "F.SilkS")
		)
		(fp_line
			(start 3.64998 3.350006)
			(end -3.64998 3.350006)
			(stroke
				(width 0.1524)
				(type default)
			)
			(layer "F.SilkS")
		)
		(fp_line
			(start 3.64998 1.8034)
			(end 3.64998 3.350006)
			(stroke
				(width 0.1524)
				(type default)
			)
			(layer "F.SilkS")
		)
		(fp_line
			(start -3.64998 -1.8034)
			(end -3.64998 -3.350006)
			(stroke
				(width 0.1524)
				(type default)
			)
			(layer "F.SilkS")
		)
		(fp_line
			(start -3.6576 -3.350006)
			(end 3.64998 -3.350006)
			(stroke
				(width 0.1524)
				(type default)
			)
			(layer "F.SilkS")
		)
		(fp_line
			(start 3.64998 -3.350006)
			(end 3.64998 -1.8034)
			(stroke
				(width 0.1524)
				(type default)
			)
			(layer "F.SilkS")
		)
		(fp_line
			(start -3.64998 3.350006)
			(end -3.64998 -3.350006)
			(stroke
				(width 0.1)
				(type default)
			)
			(layer "F.Fab")
		)
		(fp_line
			(start 3.64998 3.350006)
			(end -3.64998 3.350006)
			(stroke
				(width 0.1)
				(type default)
			)
			(layer "F.Fab")
		)
		(fp_line
			(start -3.64998 -3.350006)
			(end 3.64998 -3.350006)
			(stroke
				(width 0.1)
				(type default)
			)
			(layer "F.Fab")
		)
		(fp_line
			(start 3.64998 -3.350006)
			(end 3.64998 3.350006)
			(stroke
				(width 0.1)
				(type default)
			)
			(layer "F.Fab")
		)
		(pad "1" smd rect
			(at -2.92481 0 270)
			(size 2.15392 3.302)
			(layers "F.Cu" "F.Mask" "F.Paste")
			(net "SW_P1V0_AUX_SW")
		)
		(pad "2" smd rect
			(at 2.92481 0 270)
			(size 2.15392 3.302)
			(layers "F.Cu" "F.Mask" "F.Paste")
			(net "P1V0_AUX")
		)
	)
	(footprint ""
		(layer "F.Cu")
		(at 53.594 -10.795 90)
		(property "Reference" "R107"
			(at 0 0 90)
			(layer "F.SilkS")
			(hide yes)
			(effects
				(font
					(size 1.27 1.27)
				)
			)
		)
		(property "Value" ""
			(at 0 0 90)
			(layer "F.Fab")
			(effects
				(font
					(size 1.27 1.27)
				)
			)
		)
		(duplicate_pad_numbers_are_jumpers no)
		(fp_line
			(start 0.7874 -0.4064)
			(end 0.7874 0.4064)
			(stroke
				(width 0.1524)
				(type default)
			)
			(layer "F.SilkS")
		)
		(fp_line
			(start -0.7874 -0.4064)
			(end 0.7874 -0.4064)
			(stroke
				(width 0.1524)
				(type default)
			)
			(layer "F.SilkS")
		)
		(fp_line
			(start 0.7874 0.4064)
			(end -0.7874 0.4064)
			(stroke
				(width 0.1524)
				(type default)
			)
			(layer "F.SilkS")
		)
		(fp_line
			(start -0.7874 0.4064)
			(end -0.7874 -0.4064)
			(stroke
				(width 0.1524)
				(type default)
			)
			(layer "F.SilkS")
		)
		(fp_line
			(start -0.12065 -0.305054)
			(end -0.12065 -0.2794)
			(stroke
				(width 0.1)
				(type default)
			)
			(layer "F.Fab")
		)
		(fp_line
			(start -0.67945 -0.305054)
			(end -0.12065 -0.305054)
			(stroke
				(width 0.1)
				(type default)
			)
			(layer "F.Fab")
		)
		(fp_line
			(start 0.67945 -0.3048)
			(end 0.67945 0.3048)
			(stroke
				(width 0.1)
				(type default)
			)
			(layer "F.Fab")
		)
		(fp_line
			(start 0.12065 -0.3048)
			(end 0.67945 -0.3048)
			(stroke
				(width 0.1)
				(type default)
			)
			(layer "F.Fab")
		)
		(fp_line
			(start 0.12065 -0.2794)
			(end 0.12065 -0.3048)
			(stroke
				(width 0.1)
				(type default)
			)
			(layer "F.Fab")
		)
		(fp_line
			(start -0.12065 -0.2794)
			(end 0.12065 -0.2794)
			(stroke
				(width 0.1)
				(type default)
			)
			(layer "F.Fab")
		)
		(fp_line
			(start 0.120396 0.2794)
			(end -0.12065 0.2794)
			(stroke
				(width 0.1)
				(type default)
			)
			(layer "F.Fab")
		)
		(fp_line
			(start -0.12065 0.2794)
			(end -0.12065 0.3048)
			(stroke
				(width 0.1)
				(type default)
			)
			(layer "F.Fab")
		)
		(fp_line
			(start 0.67945 0.3048)
			(end 0.120396 0.3048)
			(stroke
				(width 0.1)
				(type default)
			)
			(layer "F.Fab")
		)
		(fp_line
			(start 0.120396 0.3048)
			(end 0.120396 0.2794)
			(stroke
				(width 0.1)
				(type default)
			)
			(layer "F.Fab")
		)
		(fp_line
			(start -0.12065 0.3048)
			(end -0.67945 0.3048)
			(stroke
				(width 0.1)
				(type default)
			)
			(layer "F.Fab")
		)
		(fp_line
			(start -0.67945 0.3048)
			(end -0.67945 -0.305054)
			(stroke
				(width 0.1)
				(type default)
			)
			(layer "F.Fab")
		)
		(pad "1" smd circle
			(at -0.40005 0 90)
			(size 0 0)
			(layers "F.Cu" "F.Mask" "F.Paste")
			(net "LED_D21_R3")
		)
		(pad "2" smd circle
			(at 0.40005 0 90)
			(size 0 0)
			(layers "F.Cu" "F.Mask" "F.Paste")
			(net "LED_D21_R2")
		)
	)
	(footprint ""
		(layer "F.Cu")
		(at 29.27604 -70.536054 90)
		(property "Reference" "R650"
			(at 0 0 90)
			(layer "F.SilkS")
			(hide yes)
			(effects
				(font
					(size 1.27 1.27)
				)
			)
		)
		(property "Value" ""
			(at 0 0 90)
			(layer "F.Fab")
			(effects
				(font
					(size 1.27 1.27)
				)
			)
		)
		(duplicate_pad_numbers_are_jumpers no)
		(fp_line
			(start 0.7874 -0.4064)
			(end 0.7874 0.4064)
			(stroke
				(width 0.1524)
				(type default)
			)
			(layer "F.SilkS")
		)
		(fp_line
			(start -0.7874 -0.4064)
			(end 0.7874 -0.4064)
			(stroke
				(width 0.1524)
				(type default)
			)
			(layer "F.SilkS")
		)
		(fp_line
			(start 0.7874 0.4064)
			(end -0.7874 0.4064)
			(stroke
				(width 0.1524)
				(type default)
			)
			(layer "F.SilkS")
		)
		(fp_line
			(start -0.7874 0.4064)
			(end -0.7874 -0.4064)
			(stroke
				(width 0.1524)
				(type default)
			)
			(layer "F.SilkS")
		)
		(fp_line
			(start -0.12065 -0.305054)
			(end -0.12065 -0.2794)
			(stroke
				(width 0.1)
				(type default)
			)
			(layer "F.Fab")
		)
		(fp_line
			(start -0.67945 -0.305054)
			(end -0.12065 -0.305054)
			(stroke
				(width 0.1)
				(type default)
			)
			(layer "F.Fab")
		)
		(fp_line
			(start 0.67945 -0.3048)
			(end 0.67945 0.3048)
			(stroke
				(width 0.1)
				(type default)
			)
			(layer "F.Fab")
		)
		(fp_line
			(start 0.12065 -0.3048)
			(end 0.67945 -0.3048)
			(stroke
				(width 0.1)
				(type default)
			)
			(layer "F.Fab")
		)
		(fp_line
			(start 0.12065 -0.2794)
			(end 0.12065 -0.3048)
			(stroke
				(width 0.1)
				(type default)
			)
			(layer "F.Fab")
		)
		(fp_line
			(start -0.12065 -0.2794)
			(end 0.12065 -0.2794)
			(stroke
				(width 0.1)
				(type default)
			)
			(layer "F.Fab")
		)
		(fp_line
			(start 0.120396 0.2794)
			(end -0.12065 0.2794)
			(stroke
				(width 0.1)
				(type default)
			)
			(layer "F.Fab")
		)
		(fp_line
			(start -0.12065 0.2794)
			(end -0.12065 0.3048)
			(stroke
				(width 0.1)
				(type default)
			)
			(layer "F.Fab")
		)
		(fp_line
			(start 0.67945 0.3048)
			(end 0.120396 0.3048)
			(stroke
				(width 0.1)
				(type default)
			)
			(layer "F.Fab")
		)
		(fp_line
			(start 0.120396 0.3048)
			(end 0.120396 0.2794)
			(stroke
				(width 0.1)
				(type default)
			)
			(layer "F.Fab")
		)
		(fp_line
			(start -0.12065 0.3048)
			(end -0.67945 0.3048)
			(stroke
				(width 0.1)
				(type default)
			)
			(layer "F.Fab")
		)
		(fp_line
			(start -0.67945 0.3048)
			(end -0.67945 -0.305054)
			(stroke
				(width 0.1)
				(type default)
			)
			(layer "F.Fab")
		)
		(pad "1" smd circle
			(at -0.40005 0 90)
			(size 0 0)
			(layers "F.Cu" "F.Mask" "F.Paste")
			(net "BMC_EMMC_DT7")
		)
		(pad "2" smd circle
			(at 0.40005 0 90)
			(size 0 0)
			(layers "F.Cu" "F.Mask" "F.Paste")
			(net "EMMC_DT7_R")
		)
	)
)
